# T6G (Grand Teton) — schematic netlist excerpt (pin names and nets, part order shuffled) for the footprints in the layout excerpt that follows; sources: Cadence DE-HDL packaged netlist, KiCad conversion of 04192023_DAF0TMB3IC0_F0TG_MB_C_brd_V02_OCP.brd

J112  CONN160_10131762101LF  CONN160_10131762-101LF IO  pkg HSD_F160D8_P2W1-2_RDH  page 122
  A1  = RST_PERST_2_SWB_BUF_N
  A2  = GND
  A3  = HGX_DETECT_N_ISO
  A4  = GND
  A5  = RST_PERST_1_SWB_BUF_N
  A6  = GND
  A7  = PRSNT_SWB_N
  A8  = GND
  B1  = GND
  B2  = P5E_CPU1_P0_RX_BUF_DN<1>
  B3  = GND
  B4  = P5E_CPU1_P0_RX_BUF_DN<3>
  B5  = GND
  B6  = P5E_CPU1_P0_RX_BUF_DN<5>
  B7  = GND
  B8  = P5E_CPU1_P0_RX_BUF_DN<7>
  C1  = P5E_CPU1_P0_RX_BUF_DN<0>
  C2  = P5E_CPU1_P0_RX_BUF_DP<1>
  C3  = P5E_CPU1_P0_RX_BUF_DN<2>
  C4  = P5E_CPU1_P0_RX_BUF_DP<3>
  C5  = P5E_CPU1_P0_RX_BUF_DN<4>
  C6  = P5E_CPU1_P0_RX_BUF_DP<5>
  C7  = P5E_CPU1_P0_RX_BUF_DN<6>
  C8  = P5E_CPU1_P0_RX_BUF_DP<7>
  D1  = P5E_CPU1_P0_RX_BUF_DP<0>
  D2  = GND
  D3  = P5E_CPU1_P0_RX_BUF_DP<2>
  D4  = GND
  D5  = P5E_CPU1_P0_RX_BUF_DP<4>
  D6  = GND
  D7  = P5E_CPU1_P0_RX_BUF_DP<6>
  D8  = GND
  E1  = GND
  E2  = P5E_CPU1_P1_RX_BUF_DN<1>
  E3  = GND
  E4  = P5E_CPU1_P1_RX_BUF_DN<3>
  E5  = GND
  E6  = P5E_CPU1_P1_RX_BUF_DN<5>
  E7  = GND
  E8  = P5E_CPU1_P1_RX_BUF_DN<7>
  F1  = P5E_CPU1_P1_RX_BUF_DN<0>
  F2  = P5E_CPU1_P1_RX_BUF_DP<1>
  F3  = P5E_CPU1_P1_RX_BUF_DN<2>
  F4  = P5E_CPU1_P1_RX_BUF_DP<3>
  F5  = P5E_CPU1_P1_RX_BUF_DN<4>
  F6  = P5E_CPU1_P1_RX_BUF_DP<5>
  F7  = P5E_CPU1_P1_RX_BUF_DN<6>
  F8  = P5E_CPU1_P1_RX_BUF_DP<7>
  G1  = P5E_CPU1_P1_RX_BUF_DP<0>
  G2  = GND
  G3  = P5E_CPU1_P1_RX_BUF_DP<2>
  G4  = GND
  G5  = P5E_CPU1_P1_RX_BUF_DP<4>
  G6  = GND
  G7  = P5E_CPU1_P1_RX_BUF_DP<6>
  G8  = GND
  H1  = GND
  H2  = P5E_CPU1_P0_TX_BUF_C_DN<1>
  H3  = GND
  H4  = P5E_CPU1_P0_TX_BUF_C_DN<3>
  H5  = GND
  H6  = P5E_CPU1_P0_TX_BUF_C_DN<5>
  H7  = GND
  H8  = P5E_CPU1_P0_TX_BUF_C_DN<7>
  I1  = P5E_CPU1_P0_TX_BUF_C_DN<0>
  I2  = P5E_CPU1_P0_TX_BUF_C_DP<1>
  I3  = P5E_CPU1_P0_TX_BUF_C_DN<2>
  I4  = P5E_CPU1_P0_TX_BUF_C_DP<3>
  I5  = P5E_CPU1_P0_TX_BUF_C_DN<4>
  I6  = P5E_CPU1_P0_TX_BUF_C_DP<5>
  I7  = P5E_CPU1_P0_TX_BUF_C_DN<6>
  I8  = P5E_CPU1_P0_TX_BUF_C_DP<7>
  J1  = P5E_CPU1_P0_TX_BUF_C_DP<0>
  J2  = GND
  J3  = P5E_CPU1_P0_TX_BUF_C_DP<2>
  J4  = GND
  J5  = P5E_CPU1_P0_TX_BUF_C_DP<4>
  J6  = GND
  J7  = P5E_CPU1_P0_TX_BUF_C_DP<6>
  J8  = GND
  K1  = GND
  K2  = P5E_CPU1_P1_TX_BUF_C_DN<1>
  K3  = GND
  K4  = P5E_CPU1_P1_TX_BUF_C_DN<3>
  K5  = GND
  K6  = P5E_CPU1_P1_TX_BUF_C_DN<5>
  K7  = GND
  K8  = P5E_CPU1_P1_TX_BUF_C_DN<7>
  L1  = P5E_CPU1_P1_TX_BUF_C_DN<0>
  L2  = P5E_CPU1_P1_TX_BUF_C_DP<1>
  L3  = P5E_CPU1_P1_TX_BUF_C_DN<2>
  L4  = P5E_CPU1_P1_TX_BUF_C_DP<3>
  L5  = P5E_CPU1_P1_TX_BUF_C_DN<4>
  L6  = P5E_CPU1_P1_TX_BUF_C_DP<5>
  L7  = P5E_CPU1_P1_TX_BUF_C_DN<6>
  L8  = P5E_CPU1_P1_TX_BUF_C_DP<7>
  M1  = P5E_CPU1_P1_TX_BUF_C_DP<0>
  M2  = GND
  M3  = P5E_CPU1_P1_TX_BUF_C_DP<2>
  M4  = GND
  M5  = P5E_CPU1_P1_TX_BUF_C_DP<4>
  M6  = GND
  M7  = P5E_CPU1_P1_TX_BUF_C_DP<6>
  M8  = GND
  N1  = GND
  N2  = NC_J112_N2
  N3  = GND
  N4  = CLK_100M_CPU0_CLK11_DN
  N5  = GND
  N6  = P2E_MB_BMC_RX_DP<0>
  N7  = GND
  N8  = P3E_CPU1_P5_RX_DN<0>
  O1  = CLK_100M_CPU1_CLK01_DN
  O2  = NC_J112_O2
  O3  = CLK_100M_CPU1_CLK11_DN
  O4  = CLK_100M_CPU0_CLK11_DP
  O5  = NC_J112_O5
  O6  = P2E_MB_BMC_RX_DN<0>
  O7  = P3E_CPU1_P5_RX_DN<1>
  O8  = P3E_CPU1_P5_RX_DP<0>
  P1  = CLK_100M_CPU1_CLK01_DP
  P2  = GND
  P3  = CLK_100M_CPU1_CLK11_DP
  P4  = GND
  P5  = NC_J112_P5
  P6  = GND
  P7  = P3E_CPU1_P5_RX_DP<1>
  P8  = GND
  Q1  = GND
  Q2  = CLK_100M_GPU_FPGA_DN
  Q3  = GND
  Q4  = SMB_1_BMC_GPU_BUF_SCL
  Q5  = GND
  Q6  = P2E_MB_BMC_TX_BUF_C_DP<0>
  Q7  = GND
  Q8  = P3E_CPU1_P5_TX_C_DN<0>
  R1  = USB2_HUB_BUF_SWB_DN
  R2  = CLK_100M_GPU_FPGA_DP
  R3  = SMB_2_BMC_GPU_BUF_SCL
  R4  = SMB_1_BMC_GPU_BUF_SDA
  R5  = NC_J112_R5
  R6  = P2E_MB_BMC_TX_BUF_C_DN<0>
  R7  = P3E_CPU1_P5_TX_C_DP<1>
  R8  = P3E_CPU1_P5_TX_C_DP<0>
  S1  = USB2_HUB_BUF_SWB_DP
  S2  = GND
  S3  = SMB_2_BMC_GPU_BUF_SDA
  S4  = GND
  S5  = NC_J112_S5
  S6  = GND
  S7  = P3E_CPU1_P5_TX_C_DN<1>
  S8  = GND
  T1  = GND
  T2  = GPU_FPGA_READY
  T3  = GND
  T4  = GPU_NVS_PWR_BRAKE_N_BUF
  T5  = GND
  T6  = GPU_FPGA_THERM_OVERT_N
  T7  = GND
  T8  = RST_PERST_0_SWB_BUF_N

(kicad_pcb
	(version 20260206)
	(generator "pcbnew")
	(generator_version "10.0")
	(general
		(thickness 1.6)
		(legacy_teardrops no)
	)
	(paper "A4")
	(title_block
		(title "04192023_DAF0TMB3IC0_F0TG_MB_C_brd_V02_OCP.brd")
		(comment 1 "Grand Teton / footprint 625 of 8354 (J112), pads 63-74 of 74")
	)
	(layers
		(0 "F.Cu" signal "TOP")
		(4 "In1.Cu" signal "GND")
		(6 "In2.Cu" signal "IN1")
		(8 "In3.Cu" signal "GND1")
		(10 "In4.Cu" signal "IN2")
		(12 "In5.Cu" signal "GND2")
		(14 "In6.Cu" signal "IN3")
		(16 "In7.Cu" signal "GND3")
		(18 "In8.Cu" signal "VCC")
		(20 "In9.Cu" signal "VCC1")
		(22 "In10.Cu" signal "GND4")
		(24 "In11.Cu" signal "IN4")
		(26 "In12.Cu" signal "GND5")
		(28 "In13.Cu" signal "IN5")
		(30 "In14.Cu" signal "GND6")
		(32 "In15.Cu" signal "IN6")
		(34 "In16.Cu" signal "GND7")
		(2 "B.Cu" signal "BOTTOM")
		(9 "F.Adhes" user "F.Adhesive")
		(11 "B.Adhes" user "B.Adhesive")
		(13 "F.Paste" user "Package Geometry/Pastemask Top")
		(15 "B.Paste" user "Package Geometry/Pastemask Bottom")
		(5 "F.SilkS" user "Ref Des/Silkscreen Top")
		(7 "B.SilkS" user "Ref Des/Silkscreen Bottom")
		(1 "F.Mask" user "Board Geometry/Soldermask Top")
		(3 "B.Mask" user "Board Geometry/Soldermask Bottom")
		(17 "Dwgs.User" user "User.Drawings")
		(19 "Cmts.User" user "User.Comments")
		(21 "Eco1.User" user "User.Eco1")
		(23 "Eco2.User" user "User.Eco2")
		(25 "Edge.Cuts" user "Board Geometry/Outline")
		(27 "Margin" user)
		(31 "F.CrtYd" user "Package Geometry/Place Bound Top")
		(29 "B.CrtYd" user "Package Geometry/Place Bound Bottom")
		(35 "F.Fab" user "Ref Des/Assembly Top")
		(33 "B.Fab" user "Ref Des/Assembly Bottom")
	)
	(footprint ""
		(layer "F.Cu")
		(at 58.64987 -440.489848)
		(property "Reference" "J112"
			(at -4.958842 26.716736 90)
			(unlocked yes)
			(layer "F.SilkS")
			(effects
				(font
					(size 0.7874 0.5842)
					(thickness 0.1524)
				)
				(justify left)
			)
		)
		(property "Value" ""
			(at 0 0 0)
			(layer "F.Fab")
			(effects
				(font
					(size 1.27 1.27)
				)
			)
		)
		(duplicate_pad_numbers_are_jumpers no)
		(pad "S4" thru_hole circle
			(at 5.999988 21.800058 180)
			(size 0.906272 0.906272)
			(drill 0.499872)
			(layers "*.Cu" "*.Mask")
			(remove_unused_layers no)
			(net "GND")
			(clearance 0.0508)
			(thermal_gap 0.0508)
		)
		(pad "S5" thru_hole circle
			(at 7.999984 21.599906 180)
			(size 0.766318 0.766318)
			(drill 0.359918)
			(layers "*.Cu" "*.Mask")
			(remove_unused_layers no)
			(net "NC_J112_S5")
			(clearance 0.0508)
			(thermal_gap 0.0508)
		)
		(pad "S6" thru_hole circle
			(at 9.99998 21.800058 180)
			(size 0.906272 0.906272)
			(drill 0.499872)
			(layers "*.Cu" "*.Mask")
			(remove_unused_layers no)
			(net "GND")
			(clearance 0.0508)
			(thermal_gap 0.0508)
		)
		(pad "S8" thru_hole circle
			(at 13.999972 21.800058 180)
			(size 0.906272 0.906272)
			(drill 0.499872)
			(layers "*.Cu" "*.Mask")
			(remove_unused_layers no)
			(net "GND")
			(clearance 0.0508)
			(thermal_gap 0.0508)
		)
		(pad "T1" thru_hole circle
			(at 0 22.800056 180)
			(size 0.906272 0.906272)
			(drill 0.499872)
			(layers "*.Cu" "*.Mask")
			(remove_unused_layers no)
			(net "GND")
			(clearance 0.0508)
			(thermal_gap 0.0508)
		)
		(pad "T2" thru_hole circle
			(at 1.999996 22.999954 180)
			(size 0.766318 0.766318)
			(drill 0.359918)
			(layers "*.Cu" "*.Mask")
			(remove_unused_layers no)
			(net "GPU_FPGA_READY")
			(clearance 0.0508)
			(thermal_gap 0.0508)
		)
		(pad "T3" thru_hole circle
			(at 3.999992 22.800056 180)
			(size 0.906272 0.906272)
			(drill 0.499872)
			(layers "*.Cu" "*.Mask")
			(remove_unused_layers no)
			(net "GND")
			(clearance 0.0508)
			(thermal_gap 0.0508)
		)
		(pad "T4" thru_hole circle
			(at 5.999988 22.999954 180)
			(size 0.766318 0.766318)
			(drill 0.359918)
			(layers "*.Cu" "*.Mask")
			(remove_unused_layers no)
			(net "GPU_NVS_PWR_BRAKE_N_BUF")
			(clearance 0.0508)
			(thermal_gap 0.0508)
		)
		(pad "T5" thru_hole circle
			(at 7.999984 22.800056 180)
			(size 0.906272 0.906272)
			(drill 0.499872)
			(layers "*.Cu" "*.Mask")
			(remove_unused_layers no)
			(net "GND")
			(clearance 0.0508)
			(thermal_gap 0.0508)
		)
		(pad "T6" thru_hole circle
			(at 9.99998 22.999954 180)
			(size 0.766318 0.766318)
			(drill 0.359918)
			(layers "*.Cu" "*.Mask")
			(remove_unused_layers no)
			(net "GPU_FPGA_THERM_OVERT_N")
			(clearance 0.0508)
			(thermal_gap 0.0508)
		)
		(pad "T7" thru_hole circle
			(at 11.999976 22.800056 180)
			(size 0.906272 0.906272)
			(drill 0.499872)
			(layers "*.Cu" "*.Mask")
			(remove_unused_layers no)
			(net "GND")
			(clearance 0.0508)
			(thermal_gap 0.0508)
		)
		(pad "T8" thru_hole circle
			(at 13.999972 22.999954 180)
			(size 0.766318 0.766318)
			(drill 0.359918)
			(layers "*.Cu" "*.Mask")
			(remove_unused_layers no)
			(net "RST_PERST_0_SWB_BUF_N")
			(clearance 0.0508)
			(thermal_gap 0.0508)
		)
	)
)
